(kicad_pcb
	(version 20260206)
	(generator "pcbnew")
	(generator_version "10.0")
	(general
		(thickness 1.6)
		(legacy_teardrops no)
	)
	(paper "A4")
	(title_block
		(title "baseboard — 13948-1b.1110WZS1818.brd")
		(comment 1 "Honey Badger (Wiwynn) / footprints 1197-1204 of 2523")
	)
	(layers
		(0 "F.Cu" signal "TOP")
		(4 "In1.Cu" signal "L2GND")
		(6 "In2.Cu" signal "L3")
		(8 "In3.Cu" signal "L4VCC")
		(10 "In4.Cu" signal "L5VCC")
		(12 "In5.Cu" signal "L6")
		(14 "In6.Cu" signal "L7GND")
		(2 "B.Cu" signal "BOTTOM")
		(9 "F.Adhes" user "F.Adhesive")
		(11 "B.Adhes" user "B.Adhesive")
		(13 "F.Paste" user "Package Geometry/Pastemask Top")
		(15 "B.Paste" user "Package Geometry/Pastemask Bottom")
		(5 "F.SilkS" user "Ref Des/Silkscreen Top")
		(7 "B.SilkS" user "Ref Des/Silkscreen Bottom")
		(1 "F.Mask" user "Board Geometry/Soldermask Top")
		(3 "B.Mask" user "Board Geometry/Soldermask Bottom")
		(17 "Dwgs.User" user "User.Drawings")
		(19 "Cmts.User" user "User.Comments")
		(21 "Eco1.User" user "User.Eco1")
		(23 "Eco2.User" user "User.Eco2")
		(25 "Edge.Cuts" user "Board Geometry/Outline")
		(27 "Margin" user)
		(31 "F.CrtYd" user "Package Geometry/Place Bound Top")
		(29 "B.CrtYd" user "Package Geometry/Place Bound Bottom")
		(35 "F.Fab" user "Ref Des/Assembly Top")
		(33 "B.Fab" user "Ref Des/Assembly Bottom")
	)
	(footprint ""
		(layer "F.Cu")
		(at 266.065 -173.99 90)
		(property "Reference" "R542"
			(at 0 0 90)
			(layer "F.SilkS")
			(hide yes)
			(effects
				(font
					(size 1.27 1.27)
				)
			)
		)
		(property "Value" "10KR2F-2-GP"
			(at 0.064008 -3.993896 90)
			(unlocked yes)
			(layer "F.Fab")
			(hide yes)
			(effects
				(font
					(size 1.016 1.016)
					(thickness 0.1524)
				)
			)
		)
		(property "Device Type" "R402H16"
			(at 0.064008 -5.517896 90)
			(unlocked yes)
			(layer "F.Fab")
			(hide yes)
			(effects
				(font
					(size 1.016 1.016)
					(thickness 0.1524)
				)
			)
		)
		(duplicate_pad_numbers_are_jumpers no)
		(fp_line
			(start 0.508 -0.9398)
			(end -0.508 -0.9398)
			(stroke
				(width 0.1524)
				(type default)
			)
			(layer "F.SilkS")
		)
		(fp_line
			(start -0.508 -0.9398)
			(end -0.508 0.9398)
			(stroke
				(width 0.1524)
				(type default)
			)
			(layer "F.SilkS")
		)
		(fp_rect
			(start -0.508 0.9398)
			(end 0.508 -0.9398)
			(stroke
				(width 0)
				(type default)
			)
			(fill no)
			(layer "F.CrtYd")
		)
		(fp_rect
			(start -0.508 0.9398)
			(end 0.508 -0.9398)
			(stroke
				(width 0)
				(type default)
			)
			(fill no)
			(layer "F.Fab")
		)
		(pad "1" smd custom
			(at 0 -0.4445 90)
			(size 0.1397 0.1397)
			(layers "F.Cu" "F.Mask" "F.Paste")
			(net "P3V3_STBY")
			(options
				(clearance outline)
				(anchor circle)
			)
			(primitives
				(gr_poly
					(pts
						(arc
							(start -0.1778 -0.2794)
							(mid -0.249642 -0.249642)
							(end -0.2794 -0.1778)
						)
						(arc
							(start -0.2794 0.1778)
							(mid -0.249642 0.249642)
							(end -0.1778 0.2794)
						)
						(arc
							(start 0.1778 0.2794)
							(mid 0.249642 0.249642)
							(end 0.2794 0.1778)
						)
						(arc
							(start 0.2794 -0.1778)
							(mid 0.249642 -0.249642)
							(end 0.1778 -0.2794)
						)
					)
					(width 0)
					(fill yes)
				)
			)
		)
		(pad "2" smd custom
			(at 0 0.4445 90)
			(size 0.1397 0.1397)
			(layers "F.Cu" "F.Mask" "F.Paste")
			(net "NIC_SMBUS_ALERT_N")
			(options
				(clearance outline)
				(anchor circle)
			)
			(primitives
				(gr_poly
					(pts
						(arc
							(start -0.1778 -0.2794)
							(mid -0.249642 -0.249642)
							(end -0.2794 -0.1778)
						)
						(arc
							(start -0.2794 0.1778)
							(mid -0.249642 0.249642)
							(end -0.1778 0.2794)
						)
						(arc
							(start 0.1778 0.2794)
							(mid 0.249642 0.249642)
							(end 0.2794 0.1778)
						)
						(arc
							(start 0.2794 -0.1778)
							(mid 0.249642 -0.249642)
							(end 0.1778 -0.2794)
						)
					)
					(width 0)
					(fill yes)
				)
			)
		)
	)
	(footprint ""
		(layer "F.Cu")
		(at 173.072044 -29.200856 90)
		(property "Reference" "R397"
			(at 0 0 90)
			(layer "F.SilkS")
			(hide yes)
			(effects
				(font
					(size 1.27 1.27)
				)
			)
		)
		(property "Value" "49D9R5F-2-GP"
			(at 0 -8.9535 90)
			(unlocked yes)
			(layer "F.Fab")
			(hide yes)
			(effects
				(font
					(size 1.27 1.016)
					(thickness 0.1524)
				)
			)
		)
		(property "Device Type" "R805H24"
			(at 0 -10.6299 90)
			(unlocked yes)
			(layer "F.Fab")
			(hide yes)
			(effects
				(font
					(size 1.27 1.016)
					(thickness 0.1524)
				)
			)
		)
		(duplicate_pad_numbers_are_jumpers no)
		(fp_line
			(start 0.889 -1.7018)
			(end -0.889 -1.7018)
			(stroke
				(width 0.1524)
				(type default)
			)
			(layer "F.SilkS")
		)
		(fp_line
			(start 0.889 -1.7018)
			(end 0.889 -0.381)
			(stroke
				(width 0.1524)
				(type default)
			)
			(layer "F.SilkS")
		)
		(fp_line
			(start -0.889 -1.7018)
			(end -0.889 0.2794)
			(stroke
				(width 0.1524)
				(type default)
			)
			(layer "F.SilkS")
		)
		(fp_line
			(start -0.889 0.0762)
			(end -0.889 1.7018)
			(stroke
				(width 0.1524)
				(type default)
			)
			(layer "F.SilkS")
		)
		(fp_line
			(start 0.889 1.7018)
			(end 0.889 -0.508)
			(stroke
				(width 0.1524)
				(type default)
			)
			(layer "F.SilkS")
		)
		(fp_line
			(start -0.889 1.7018)
			(end 0.889 1.7018)
			(stroke
				(width 0.1524)
				(type default)
			)
			(layer "F.SilkS")
		)
		(fp_poly
			(pts
				(xy 0.9652 -1.778) (xy 0.9652 1.778) (xy -0.9652 1.778) (xy -0.9652 -1.778)
			)
			(stroke
				(width 0)
				(type default)
			)
			(fill no)
			(layer "F.CrtYd")
		)
		(fp_rect
			(start -0.9652 1.778)
			(end 0.9652 -1.778)
			(stroke
				(width 0)
				(type default)
			)
			(fill no)
			(layer "F.Fab")
		)
		(pad "1" smd rect
			(at 0 -0.9652 90)
			(size 1.397 1.143)
			(layers "F.Cu" "F.Mask" "F.Paste")
			(net "P3V3_STBY")
		)
		(pad "2" smd rect
			(at 0 0.9652 90)
			(size 1.397 1.143)
			(layers "F.Cu" "F.Mask" "F.Paste")
			(net "BCM5221_TX_C_DN")
		)
	)
	(footprint ""
		(layer "F.Cu")
		(at 198.755 -95.885 -90)
		(property "Reference" "PC237"
			(at 0 0 270)
			(layer "F.SilkS")
			(hide yes)
			(effects
				(font
					(size 1.27 1.27)
				)
			)
		)
		(property "Value" "SC47U6D3V5MX-1-GP"
			(at -0.0762 -6.1214 270)
			(unlocked yes)
			(layer "F.Fab")
			(hide yes)
			(effects
				(font
					(size 1.016 1.016)
					(thickness 0.1524)
				)
			)
		)
		(property "Device Type" "C805H54"
			(at -0.0762 -8.1534 270)
			(unlocked yes)
			(layer "F.Fab")
			(hide yes)
			(effects
				(font
					(size 1.016 1.016)
					(thickness 0.1524)
				)
			)
		)
		(duplicate_pad_numbers_are_jumpers no)
		(fp_line
			(start 0.635 0)
			(end -0.635 0)
			(stroke
				(width 0.508)
				(type default)
			)
			(layer "F.SilkS")
		)
		(fp_rect
			(start -0.9652 1.778)
			(end 0.9652 -1.778)
			(stroke
				(width 0)
				(type default)
			)
			(fill no)
			(layer "F.CrtYd")
		)
		(fp_poly
			(pts
				(xy -0.9652 -1.778) (xy 0.9652 -1.778) (xy 0.9652 1.778) (xy -0.9652 1.778)
			)
			(stroke
				(width 0)
				(type default)
			)
			(fill no)
			(layer "F.Fab")
		)
		(pad "1" smd rect
			(at 0 -0.9652 270)
			(size 1.397 1.143)
			(layers "F.Cu" "F.Mask" "F.Paste")
			(net "P1V5_E")
		)
		(pad "2" smd rect
			(at 0 0.9652 270)
			(size 1.397 1.143)
			(layers "F.Cu" "F.Mask" "F.Paste")
			(net "GND")
		)
	)
	(footprint ""
		(layer "F.Cu")
		(at 87.26297 -112.014 180)
		(property "Reference" "SC1236"
			(at 0 0 180)
			(layer "F.SilkS")
			(hide yes)
			(effects
				(font
					(size 1.27 1.27)
				)
			)
		)
		(property "Value" "SCD1U6D3V1KX-GP"
			(at -2.8321 -1.7399 180)
			(unlocked yes)
			(layer "F.Fab")
			(hide yes)
			(effects
				(font
					(size 1.016 1.016)
					(thickness 0.1524)
				)
			)
		)
		(property "Device Type" "C0201H13"
			(at -2.8321 -3.2639 180)
			(unlocked yes)
			(layer "F.Fab")
			(hide yes)
			(effects
				(font
					(size 1.016 1.016)
					(thickness 0.1524)
				)
			)
		)
		(duplicate_pad_numbers_are_jumpers no)
		(fp_rect
			(start -0.2794 0.6477)
			(end 0.2794 -0.6477)
			(stroke
				(width 0)
				(type default)
			)
			(fill no)
			(layer "F.CrtYd")
		)
		(fp_rect
			(start -0.2794 0.6477)
			(end 0.2794 -0.6477)
			(stroke
				(width 0)
				(type default)
			)
			(fill no)
			(layer "F.Fab")
		)
		(pad "1" smd custom
			(at 0 -0.2794 180)
			(size 0.0762 0.0762)
			(layers "F.Cu" "F.Mask" "F.Paste")
			(net "P1V8_E")
			(options
				(clearance outline)
				(anchor circle)
			)
			(primitives
				(gr_poly
					(pts
						(arc
							(start 0.1524 -0.127)
							(mid 0.137521 -0.162921)
							(end 0.1016 -0.1778)
						)
						(arc
							(start -0.1016 -0.1778)
							(mid -0.137521 -0.162921)
							(end -0.1524 -0.127)
						)
						(arc
							(start -0.1524 0.127)
							(mid -0.137521 0.162921)
							(end -0.1016 0.1778)
						)
						(arc
							(start 0.1016 0.1778)
							(mid 0.137521 0.162921)
							(end 0.1524 0.127)
						)
					)
					(width 0)
					(fill yes)
				)
			)
		)
		(pad "2" smd custom
			(at 0 0.2794 180)
			(size 0.0762 0.0762)
			(layers "F.Cu" "F.Mask" "F.Paste")
			(net "GND")
			(options
				(clearance outline)
				(anchor circle)
			)
			(primitives
				(gr_poly
					(pts
						(arc
							(start 0.1524 -0.127)
							(mid 0.137521 -0.162921)
							(end 0.1016 -0.1778)
						)
						(arc
							(start -0.1016 -0.1778)
							(mid -0.137521 -0.162921)
							(end -0.1524 -0.127)
						)
						(arc
							(start -0.1524 0.127)
							(mid -0.137521 0.162921)
							(end -0.1016 0.1778)
						)
						(arc
							(start 0.1016 0.1778)
							(mid 0.137521 0.162921)
							(end 0.1524 0.127)
						)
					)
					(width 0)
					(fill yes)
				)
			)
		)
	)
	(footprint ""
		(layer "F.Cu")
		(at 112.973612 -204.978)
		(property "Reference" "SR877"
			(at 0 0 0)
			(layer "F.SilkS")
			(hide yes)
			(effects
				(font
					(size 1.27 1.27)
				)
			)
		)
		(property "Value" "0R2J-2-GP"
			(at 0.064008 -3.993896 0)
			(unlocked yes)
			(layer "F.Fab")
			(hide yes)
			(effects
				(font
					(size 1.016 1.016)
					(thickness 0.1524)
				)
			)
		)
		(property "Device Type" "R402H16"
			(at 0.064008 -5.517896 0)
			(unlocked yes)
			(layer "F.Fab")
			(hide yes)
			(effects
				(font
					(size 1.016 1.016)
					(thickness 0.1524)
				)
			)
		)
		(duplicate_pad_numbers_are_jumpers no)
		(fp_line
			(start -0.508 -0.9398)
			(end -0.508 0.9398)
			(stroke
				(width 0.1524)
				(type default)
			)
			(layer "F.SilkS")
		)
		(fp_line
			(start 0.508 -0.9398)
			(end -0.508 -0.9398)
			(stroke
				(width 0.1524)
				(type default)
			)
			(layer "F.SilkS")
		)
		(fp_rect
			(start -0.508 0.9398)
			(end 0.508 -0.9398)
			(stroke
				(width 0)
				(type default)
			)
			(fill no)
			(layer "F.CrtYd")
		)
		(fp_rect
			(start -0.508 0.9398)
			(end 0.508 -0.9398)
			(stroke
				(width 0)
				(type default)
			)
			(fill no)
			(layer "F.Fab")
		)
		(pad "1" smd custom
			(at 0 -0.4445)
			(size 0.1397 0.1397)
			(layers "F.Cu" "F.Mask" "F.Paste")
			(net "SAS_HDD_REDV_TX8_P")
			(options
				(clearance outline)
				(anchor circle)
			)
			(primitives
				(gr_poly
					(pts
						(arc
							(start -0.1778 -0.2794)
							(mid -0.249642 -0.249642)
							(end -0.2794 -0.1778)
						)
						(arc
							(start -0.2794 0.1778)
							(mid -0.249642 0.249642)
							(end -0.1778 0.2794)
						)
						(arc
							(start 0.1778 0.2794)
							(mid 0.249642 0.249642)
							(end 0.2794 0.1778)
						)
						(arc
							(start 0.2794 -0.1778)
							(mid 0.249642 -0.249642)
							(end 0.1778 -0.2794)
						)
					)
					(width 0)
					(fill yes)
				)
			)
		)
		(pad "2" smd custom
			(at 0 0.4445)
			(size 0.1397 0.1397)
			(layers "F.Cu" "F.Mask" "F.Paste")
			(net "SAS_HDD_REDV_SER_TX8_P")
			(options
				(clearance outline)
				(anchor circle)
			)
			(primitives
				(gr_poly
					(pts
						(arc
							(start -0.1778 -0.2794)
							(mid -0.249642 -0.249642)
							(end -0.2794 -0.1778)
						)
						(arc
							(start -0.2794 0.1778)
							(mid -0.249642 0.249642)
							(end -0.1778 0.2794)
						)
						(arc
							(start 0.1778 0.2794)
							(mid 0.249642 0.249642)
							(end 0.2794 0.1778)
						)
						(arc
							(start 0.2794 -0.1778)
							(mid 0.249642 -0.249642)
							(end 0.1778 -0.2794)
						)
					)
					(width 0)
					(fill yes)
				)
			)
		)
	)
	(footprint ""
		(layer "F.Cu")
		(at 20.651216 -181.91988)
		(property "Reference" "R649"
			(at 0 0 0)
			(layer "F.SilkS")
			(hide yes)
			(effects
				(font
					(size 1.27 1.27)
				)
			)
		)
		(property "Value" "4K7R2F-GP"
			(at 0.064008 -3.993896 0)
			(unlocked yes)
			(layer "F.Fab")
			(hide yes)
			(effects
				(font
					(size 1.016 1.016)
					(thickness 0.1524)
				)
			)
		)
		(property "Device Type" "R402H16"
			(at 0.064008 -5.517896 0)
			(unlocked yes)
			(layer "F.Fab")
			(hide yes)
			(effects
				(font
					(size 1.016 1.016)
					(thickness 0.1524)
				)
			)
		)
		(duplicate_pad_numbers_are_jumpers no)
		(fp_line
			(start -0.508 -0.9398)
			(end -0.508 0.9398)
			(stroke
				(width 0.1524)
				(type default)
			)
			(layer "F.SilkS")
		)
		(fp_line
			(start 0.508 -0.9398)
			(end -0.508 -0.9398)
			(stroke
				(width 0.1524)
				(type default)
			)
			(layer "F.SilkS")
		)
		(fp_rect
			(start -0.508 0.9398)
			(end 0.508 -0.9398)
			(stroke
				(width 0)
				(type default)
			)
			(fill no)
			(layer "F.CrtYd")
		)
		(fp_rect
			(start -0.508 0.9398)
			(end 0.508 -0.9398)
			(stroke
				(width 0)
				(type default)
			)
			(fill no)
			(layer "F.Fab")
		)
		(pad "1" smd custom
			(at 0 -0.4445)
			(size 0.1397 0.1397)
			(layers "F.Cu" "F.Mask" "F.Paste")
			(net "IO_EXP_HDD_PRE_A3")
			(options
				(clearance outline)
				(anchor circle)
			)
			(primitives
				(gr_poly
					(pts
						(arc
							(start -0.1778 -0.2794)
							(mid -0.249642 -0.249642)
							(end -0.2794 -0.1778)
						)
						(arc
							(start -0.2794 0.1778)
							(mid -0.249642 0.249642)
							(end -0.1778 0.2794)
						)
						(arc
							(start 0.1778 0.2794)
							(mid 0.249642 0.249642)
							(end 0.2794 0.1778)
						)
						(arc
							(start 0.2794 -0.1778)
							(mid 0.249642 -0.249642)
							(end 0.1778 -0.2794)
						)
					)
					(width 0)
					(fill yes)
				)
			)
		)
		(pad "2" smd custom
			(at 0 0.4445)
			(size 0.1397 0.1397)
			(layers "F.Cu" "F.Mask" "F.Paste")
			(net "GND")
			(options
				(clearance outline)
				(anchor circle)
			)
			(primitives
				(gr_poly
					(pts
						(arc
							(start -0.1778 -0.2794)
							(mid -0.249642 -0.249642)
							(end -0.2794 -0.1778)
						)
						(arc
							(start -0.2794 0.1778)
							(mid -0.249642 0.249642)
							(end -0.1778 0.2794)
						)
						(arc
							(start 0.1778 0.2794)
							(mid 0.249642 0.249642)
							(end 0.2794 0.1778)
						)
						(arc
							(start 0.2794 -0.1778)
							(mid 0.249642 -0.249642)
							(end 0.1778 -0.2794)
						)
					)
					(width 0)
					(fill yes)
				)
			)
		)
	)
	(footprint ""
		(layer "F.Cu")
		(at 47.498 -218.694 -90)
		(property "Reference" "C7277"
			(at 0 0 270)
			(layer "F.SilkS")
			(hide yes)
			(effects
				(font
					(size 1.27 1.27)
				)
			)
		)
		(property "Value" "SC1U16V3KX-5GP"
			(at 0 -2.8194 270)
			(unlocked yes)
			(layer "F.Fab")
			(hide yes)
			(effects
				(font
					(size 1.016 1.016)
					(thickness 0.1524)
				)
			)
		)
		(property "Device Type" "C603H36"
			(at 0 -4.3434 270)
			(unlocked yes)
			(layer "F.Fab")
			(hide yes)
			(effects
				(font
					(size 1.016 1.016)
					(thickness 0.1524)
				)
			)
		)
		(duplicate_pad_numbers_are_jumpers no)
		(fp_line
			(start 0.508 0)
			(end -0.508 0)
			(stroke
				(width 0.2032)
				(type default)
			)
			(layer "F.SilkS")
		)
		(fp_rect
			(start -0.5842 1.3335)
			(end 0.5842 -1.3335)
			(stroke
				(width 0)
				(type default)
			)
			(fill no)
			(layer "F.CrtYd")
		)
		(fp_rect
			(start -0.5842 1.3335)
			(end 0.5842 -1.3335)
			(stroke
				(width 0)
				(type default)
			)
			(fill no)
			(layer "F.Fab")
		)
		(pad "1" smd custom
			(at 0 -0.762 270)
			(size 0.2159 0.2159)
			(layers "F.Cu" "F.Mask" "F.Paste")
			(net "MB0_VCAP_R")
			(options
				(clearance outline)
				(anchor circle)
			)
			(primitives
				(gr_poly
					(pts
						(arc
							(start -0.3302 -0.4318)
							(mid -0.402042 -0.402042)
							(end -0.4318 -0.3302)
						)
						(arc
							(start -0.4318 0.3302)
							(mid -0.402042 0.402042)
							(end -0.3302 0.4318)
						)
						(arc
							(start 0.3302 0.4318)
							(mid 0.402042 0.402042)
							(end 0.4318 0.3302)
						)
						(arc
							(start 0.4318 -0.3302)
							(mid 0.402042 -0.402042)
							(end 0.3302 -0.4318)
						)
					)
					(width 0)
					(fill yes)
				)
			)
		)
		(pad "2" smd custom
			(at 0 0.762 270)
			(size 0.2159 0.2159)
			(layers "F.Cu" "F.Mask" "F.Paste")
			(net "AGND_CURRENT_MON")
			(options
				(clearance outline)
				(anchor circle)
			)
			(primitives
				(gr_poly
					(pts
						(arc
							(start -0.3302 -0.4318)
							(mid -0.402042 -0.402042)
							(end -0.4318 -0.3302)
						)
						(arc
							(start -0.4318 0.3302)
							(mid -0.402042 0.402042)
							(end -0.3302 0.4318)
						)
						(arc
							(start 0.3302 0.4318)
							(mid 0.402042 0.402042)
							(end 0.4318 0.3302)
						)
						(arc
							(start 0.4318 -0.3302)
							(mid 0.402042 -0.402042)
							(end 0.3302 -0.4318)
						)
					)
					(width 0)
					(fill yes)
				)
			)
		)
	)
	(footprint ""
		(layer "F.Cu")
		(at 274.193 -165.608 90)
		(property "Reference" "R330"
			(at 0 0 90)
			(layer "F.SilkS")
			(hide yes)
			(effects
				(font
					(size 1.27 1.27)
				)
			)
		)
		(property "Value" "0R2J-2-GP"
			(at 0.064008 -3.993896 90)
			(unlocked yes)
			(layer "F.Fab")
			(hide yes)
			(effects
				(font
					(size 1.016 1.016)
					(thickness 0.1524)
				)
			)
		)
		(property "Device Type" "R402H16"
			(at 0.064008 -5.517896 90)
			(unlocked yes)
			(layer "F.Fab")
			(hide yes)
			(effects
				(font
					(size 1.016 1.016)
					(thickness 0.1524)
				)
			)
		)
		(duplicate_pad_numbers_are_jumpers no)
		(fp_line
			(start 0.508 -0.9398)
			(end -0.508 -0.9398)
			(stroke
				(width 0.1524)
				(type default)
			)
			(layer "F.SilkS")
		)
		(fp_line
			(start -0.508 -0.9398)
			(end -0.508 0.9398)
			(stroke
				(width 0.1524)
				(type default)
			)
			(layer "F.SilkS")
		)
		(fp_rect
			(start -0.508 0.9398)
			(end 0.508 -0.9398)
			(stroke
				(width 0)
				(type default)
			)
			(fill no)
			(layer "F.CrtYd")
		)
		(fp_rect
			(start -0.508 0.9398)
			(end 0.508 -0.9398)
			(stroke
				(width 0)
				(type default)
			)
			(fill no)
			(layer "F.Fab")
		)
		(pad "1" smd custom
			(at 0 -0.4445 90)
			(size 0.1397 0.1397)
			(layers "F.Cu" "F.Mask" "F.Paste")
			(net "BMC_RSTBTN_N")
			(options
				(clearance outline)
				(anchor circle)
			)
			(primitives
				(gr_poly
					(pts
						(arc
							(start -0.1778 -0.2794)
							(mid -0.249642 -0.249642)
							(end -0.2794 -0.1778)
						)
						(arc
							(start -0.2794 0.1778)
							(mid -0.249642 0.249642)
							(end -0.1778 0.2794)
						)
						(arc
							(start 0.1778 0.2794)
							(mid 0.249642 0.249642)
							(end 0.2794 0.1778)
						)
						(arc
							(start 0.2794 -0.1778)
							(mid 0.249642 -0.249642)
							(end 0.1778 -0.2794)
						)
					)
					(width 0)
					(fill yes)
				)
			)
		)
		(pad "2" smd custom
			(at 0 0.4445 90)
			(size 0.1397 0.1397)
			(layers "F.Cu" "F.Mask" "F.Paste")
			(net "BMC_RSTBTN_N_R")
			(options
				(clearance outline)
				(anchor circle)
			)
			(primitives
				(gr_poly
					(pts
						(arc
							(start -0.1778 -0.2794)
							(mid -0.249642 -0.249642)
							(end -0.2794 -0.1778)
						)
						(arc
							(start -0.2794 0.1778)
							(mid -0.249642 0.249642)
							(end -0.1778 0.2794)
						)
						(arc
							(start 0.1778 0.2794)
							(mid 0.249642 0.249642)
							(end 0.2794 0.1778)
						)
						(arc
							(start 0.2794 -0.1778)
							(mid 0.249642 -0.249642)
							(end 0.1778 -0.2794)
						)
					)
					(width 0)
					(fill yes)
				)
			)
		)
	)
)
